# S9S_MB_2U (Grand Teton) — schematic netlist excerpt (pin names and nets, part order shuffled) for the footprints in the layout excerpt that follows; sources: Cadence DE-HDL packaged netlist, KiCad conversion of 03242023_DA0F0TMBIJ0_F0T_Motherboard_J_brd_V01_OCP.brd

R2897  Q_RES  33.2 1% CHIP  pkg 0402LF  page 234 : A = SMB_1_BMC_GPU_BUF_R_SCL ; B = SMB_1_BMC_GPU_BUF_SCL
R2669  Q_RES  10K 1% CHIP  pkg 0402LF  page 234 : A = P3V3_AUX ; B = SMB_BMC_SWB_BUF_R_SDA

(kicad_pcb
	(version 20260206)
	(generator "pcbnew")
	(generator_version "10.0")
	(general
		(thickness 1.6)
		(legacy_teardrops no)
	)
	(paper "A4")
	(title_block
		(title "03242023_DA0F0TMBIJ0_F0T_Motherboard_J_brd_V01_OCP.brd")
		(comment 1 "Grand Teton / footprints 3421-3422 of 6105")
	)
	(layers
		(0 "F.Cu" signal "TOP")
		(4 "In1.Cu" signal "GND")
		(6 "In2.Cu" signal "IN1")
		(8 "In3.Cu" signal "GND1")
		(10 "In4.Cu" signal "IN2")
		(12 "In5.Cu" signal "GND2")
		(14 "In6.Cu" signal "IN3")
		(16 "In7.Cu" signal "GND3")
		(18 "In8.Cu" signal "VCC")
		(20 "In9.Cu" signal "VCC1")
		(22 "In10.Cu" signal "GND4")
		(24 "In11.Cu" signal "IN4")
		(26 "In12.Cu" signal "GND5")
		(28 "In13.Cu" signal "IN5")
		(30 "In14.Cu" signal "GND6")
		(32 "In15.Cu" signal "IN6")
		(34 "In16.Cu" signal "GND7")
		(2 "B.Cu" signal "BOTTOM")
		(9 "F.Adhes" user "F.Adhesive")
		(11 "B.Adhes" user "B.Adhesive")
		(13 "F.Paste" user "Package Geometry/Pastemask Top")
		(15 "B.Paste" user "Package Geometry/Pastemask Bottom")
		(5 "F.SilkS" user "Ref Des/Silkscreen Top")
		(7 "B.SilkS" user "Ref Des/Silkscreen Bottom")
		(1 "F.Mask" user "Board Geometry/Soldermask Top")
		(3 "B.Mask" user "Board Geometry/Soldermask Bottom")
		(17 "Dwgs.User" user "User.Drawings")
		(19 "Cmts.User" user "User.Comments")
		(21 "Eco1.User" user "User.Eco1")
		(23 "Eco2.User" user "User.Eco2")
		(25 "Edge.Cuts" user "Board Geometry/Outline")
		(27 "Margin" user)
		(31 "F.CrtYd" user "Package Geometry/Place Bound Top")
		(29 "B.CrtYd" user "Package Geometry/Place Bound Bottom")
		(35 "F.Fab" user "Ref Des/Assembly Top")
		(33 "B.Fab" user "Ref Des/Assembly Bottom")
	)
	(footprint ""
		(layer "F.Cu")
		(at 38.02888 -435.955948 180)
		(property "Reference" "R2897"
			(at 0 0 180)
			(layer "F.SilkS")
			(hide yes)
			(effects
				(font
					(size 1.27 1.27)
				)
			)
		)
		(property "Value" ""
			(at 0 0 180)
			(layer "F.Fab")
			(effects
				(font
					(size 1.27 1.27)
				)
			)
		)
		(duplicate_pad_numbers_are_jumpers no)
		(fp_line
			(start 0.7874 0.4064)
			(end -0.7874 0.4064)
			(stroke
				(width 0.1524)
				(type default)
			)
			(layer "F.SilkS")
		)
		(fp_line
			(start 0.7874 -0.4064)
			(end 0.7874 0.4064)
			(stroke
				(width 0.1524)
				(type default)
			)
			(layer "F.SilkS")
		)
		(fp_line
			(start -0.7874 0.4064)
			(end -0.7874 -0.4064)
			(stroke
				(width 0.1524)
				(type default)
			)
			(layer "F.SilkS")
		)
		(fp_line
			(start -0.7874 -0.4064)
			(end 0.7874 -0.4064)
			(stroke
				(width 0.1524)
				(type default)
			)
			(layer "F.SilkS")
		)
		(fp_line
			(start 0.67945 0.3048)
			(end 0.120396 0.3048)
			(stroke
				(width 0.1)
				(type default)
			)
			(layer "F.Fab")
		)
		(fp_line
			(start 0.67945 -0.3048)
			(end 0.67945 0.3048)
			(stroke
				(width 0.1)
				(type default)
			)
			(layer "F.Fab")
		)
		(fp_line
			(start 0.12065 -0.2794)
			(end 0.12065 -0.3048)
			(stroke
				(width 0.1)
				(type default)
			)
			(layer "F.Fab")
		)
		(fp_line
			(start 0.12065 -0.3048)
			(end 0.67945 -0.3048)
			(stroke
				(width 0.1)
				(type default)
			)
			(layer "F.Fab")
		)
		(fp_line
			(start 0.120396 0.3048)
			(end 0.120396 0.2794)
			(stroke
				(width 0.1)
				(type default)
			)
			(layer "F.Fab")
		)
		(fp_line
			(start 0.120396 0.2794)
			(end -0.12065 0.2794)
			(stroke
				(width 0.1)
				(type default)
			)
			(layer "F.Fab")
		)
		(fp_line
			(start -0.12065 0.3048)
			(end -0.67945 0.3048)
			(stroke
				(width 0.1)
				(type default)
			)
			(layer "F.Fab")
		)
		(fp_line
			(start -0.12065 0.2794)
			(end -0.12065 0.3048)
			(stroke
				(width 0.1)
				(type default)
			)
			(layer "F.Fab")
		)
		(fp_line
			(start -0.12065 -0.2794)
			(end 0.12065 -0.2794)
			(stroke
				(width 0.1)
				(type default)
			)
			(layer "F.Fab")
		)
		(fp_line
			(start -0.12065 -0.305054)
			(end -0.12065 -0.2794)
			(stroke
				(width 0.1)
				(type default)
			)
			(layer "F.Fab")
		)
		(fp_line
			(start -0.67945 0.3048)
			(end -0.67945 -0.305054)
			(stroke
				(width 0.1)
				(type default)
			)
			(layer "F.Fab")
		)
		(fp_line
			(start -0.67945 -0.305054)
			(end -0.12065 -0.305054)
			(stroke
				(width 0.1)
				(type default)
			)
			(layer "F.Fab")
		)
		(pad "1" smd circle
			(at -0.40005 0 180)
			(size 0 0)
			(layers "F.Cu" "F.Mask" "F.Paste")
			(net "SMB_1_BMC_GPU_BUF_R_SCL")
		)
		(pad "2" smd circle
			(at 0.40005 0 180)
			(size 0 0)
			(layers "F.Cu" "F.Mask" "F.Paste")
			(net "SMB_1_BMC_GPU_BUF_SCL")
		)
	)
	(footprint ""
		(layer "F.Cu")
		(at 164.52215 -418.514276 90)
		(property "Reference" "R2669"
			(at 0 0 90)
			(layer "F.SilkS")
			(hide yes)
			(effects
				(font
					(size 1.27 1.27)
				)
			)
		)
		(property "Value" ""
			(at 0 0 90)
			(layer "F.Fab")
			(effects
				(font
					(size 1.27 1.27)
				)
			)
		)
		(duplicate_pad_numbers_are_jumpers no)
		(fp_line
			(start 0.7874 -0.4064)
			(end 0.7874 0.4064)
			(stroke
				(width 0.1524)
				(type default)
			)
			(layer "F.SilkS")
		)
		(fp_line
			(start -0.7874 -0.4064)
			(end 0.7874 -0.4064)
			(stroke
				(width 0.1524)
				(type default)
			)
			(layer "F.SilkS")
		)
		(fp_line
			(start 0.7874 0.4064)
			(end -0.7874 0.4064)
			(stroke
				(width 0.1524)
				(type default)
			)
			(layer "F.SilkS")
		)
		(fp_line
			(start -0.7874 0.4064)
			(end -0.7874 -0.4064)
			(stroke
				(width 0.1524)
				(type default)
			)
			(layer "F.SilkS")
		)
		(fp_line
			(start -0.12065 -0.305054)
			(end -0.12065 -0.2794)
			(stroke
				(width 0.1)
				(type default)
			)
			(layer "F.Fab")
		)
		(fp_line
			(start -0.67945 -0.305054)
			(end -0.12065 -0.305054)
			(stroke
				(width 0.1)
				(type default)
			)
			(layer "F.Fab")
		)
		(fp_line
			(start 0.67945 -0.3048)
			(end 0.67945 0.3048)
			(stroke
				(width 0.1)
				(type default)
			)
			(layer "F.Fab")
		)
		(fp_line
			(start 0.12065 -0.3048)
			(end 0.67945 -0.3048)
			(stroke
				(width 0.1)
				(type default)
			)
			(layer "F.Fab")
		)
		(fp_line
			(start 0.12065 -0.2794)
			(end 0.12065 -0.3048)
			(stroke
				(width 0.1)
				(type default)
			)
			(layer "F.Fab")
		)
		(fp_line
			(start -0.12065 -0.2794)
			(end 0.12065 -0.2794)
			(stroke
				(width 0.1)
				(type default)
			)
			(layer "F.Fab")
		)
		(fp_line
			(start 0.120396 0.2794)
			(end -0.12065 0.2794)
			(stroke
				(width 0.1)
				(type default)
			)
			(layer "F.Fab")
		)
		(fp_line
			(start -0.12065 0.2794)
			(end -0.12065 0.3048)
			(stroke
				(width 0.1)
				(type default)
			)
			(layer "F.Fab")
		)
		(fp_line
			(start 0.67945 0.3048)
			(end 0.120396 0.3048)
			(stroke
				(width 0.1)
				(type default)
			)
			(layer "F.Fab")
		)
		(fp_line
			(start 0.120396 0.3048)
			(end 0.120396 0.2794)
			(stroke
				(width 0.1)
				(type default)
			)
			(layer "F.Fab")
		)
		(fp_line
			(start -0.12065 0.3048)
			(end -0.67945 0.3048)
			(stroke
				(width 0.1)
				(type default)
			)
			(layer "F.Fab")
		)
		(fp_line
			(start -0.67945 0.3048)
			(end -0.67945 -0.305054)
			(stroke
				(width 0.1)
				(type default)
			)
			(layer "F.Fab")
		)
		(pad "1" smd circle
			(at -0.40005 0 90)
			(size 0 0)
			(layers "F.Cu" "F.Mask" "F.Paste")
			(net "P3V3_AUX")
		)
		(pad "2" smd circle
			(at 0.40005 0 90)
			(size 0 0)
			(layers "F.Cu" "F.Mask" "F.Paste")
			(net "SMB_BMC_SWB_BUF_R_SDA")
		)
	)
)
